FILE_TYPE = MACRO_DRAWING;
SET COLOR_WIRE YELLOW;
SET COLOR_PROP ORANGE;
SET COLOR_DOT WHITE;
SET COLOR_ARC YELLOW;
SET COLOR_BODY GREEN;
SET COLOR_NOTE PURPLE;
SET PROP_DISPLAY VALUE;
SET PAGE_NUMBER P399;
FORCEADD OFFPAGE..1
(-7175 5100);
FORCEPROP 2 LAST $XR1 186 
J 0
(-7547 5100);
DISPLAY 0.638298 (-7547 5100);
PAINT MONO (-7547 5100);
FORCEPROP 2 LAST $XR0 185 
J 0
(-7427 5100);
DISPLAY 0.638298 (-7427 5100);
PAINT MONO (-7427 5100);
FORCEPROP 2 LAST CDS_LIB standard
J 0
(-7175 5100);
DISPLAY INVISIBLE (-7175 5100);
FORCEPROP 1 LAST OFFPAGE TRUE
J 0
(-6850 4975);
DISPLAY 0.872340 (-6850 4975);
DISPLAY INVISIBLE (-6850 4975);
FORCEPROP 1 LAST COMMENT_BODY TRUE
J 0
(-7050 5000);
DISPLAY 0.872340 (-7050 5000);
PAINT GREEN (-7050 5000);
DISPLAY INVISIBLE (-7050 5000);
FORCEPROP 2 LAST PATH I1
J 0
(-7125 5175);
DISPLAY 0.680851 (-7125 5175);
DISPLAY INVISIBLE (-7125 5175);
FORCEADD P1V0..1
(-4500 6000);
FORCEPROP 3 LASTPIN (-4500 5950) SIG_NAME P1V8_CPU1_RT_1D\g
J 0
(-4490 5960);
DISPLAY 0.659574 (-4490 5960);
PAINT MONO (-4490 5960);
DISPLAY INVISIBLE (-4490 5960);
FORCEPROP 1 LAST HDL_POWER P1V8_CPU1_RT_1D
J 1
(-4500 6050);
DISPLAY 0.489362 (-4500 6050);
PAINT SKYBLUE (-4500 6050);
FORCEPROP 2 LAST CDS_LIB pure_quanta_power
J 0
(-4500 6000);
DISPLAY INVISIBLE (-4500 6000);
FORCEPROP 1 LAST PATH I10
J 0
(-4450 6025);
DISPLAY 0.872340 (-4450 6025);
PAINT AQUA (-4450 6025);
DISPLAY INVISIBLE (-4450 6025);
FORCEADD Q_CAP..1
(-4725 5700);
FORCEPROP 1 LAST LOCATION C7501
J 0
(-4675 5800);
DISPLAY 0.787234 (-4675 5800);
PAINT SKYBLUE (-4675 5800);
FORCEPROP 0 LAST $SEC 1
J 0
(-4675 5850);
DISPLAY 0.680851 (-4675 5850);
PAINT MONO (-4675 5850);
DISPLAY INVISIBLE (-4675 5850);
FORCEPROP 0 LAST CDS_SEC 1
J 0
(-4675 5850);
DISPLAY 0.680851 (-4675 5850);
DISPLAY INVISIBLE (-4675 5850);
FORCEPROP 1 LASTPIN (-4725 5800) $PN 1
J 0
(-4715 5780);
DISPLAY 0.787234 (-4715 5780);
PAINT MONO (-4715 5780);
FORCEPROP 1 LASTPIN (-4725 5600) $PN 2
J 0
(-4715 5580);
DISPLAY 0.787234 (-4715 5580);
PAINT MONO (-4715 5580);
FORCEPROP 1 LAST MATERIAL X7S
J 0
(-4675 5600);
DISPLAY 0.510638 (-4675 5600);
FORCEPROP 1 LAST TOLERANCE 10%
J 0
(-4675 5650);
DISPLAY 0.510638 (-4675 5650);
FORCEPROP 1 LAST PACK_TYPE C0201
J 0
(-4675 5550);
DISPLAY 0.510638 (-4675 5550);
FORCEPROP 1 LAST VOLTAGE 10V
J 0
(-4675 5700);
DISPLAY 0.510638 (-4675 5700);
FORCEPROP 1 LAST VALUE 0.1UF
J 0
(-4675 5750);
DISPLAY 0.510638 (-4675 5750);
FORCEPROP 2 LAST CDS_LIB pure_quanta
J 0
(-4725 5700);
DISPLAY INVISIBLE (-4725 5700);
FORCEPROP 1 LAST PATH I11
J 0
(-4675 5850);
DISPLAY 0.978723 (-4675 5850);
PAINT WHITE (-4675 5850);
DISPLAY INVISIBLE (-4675 5850);
FORCEPROP 1 LAST PART_NUMBER CH4102K6E00
J 0
(-4675 5550);
DISPLAY 0.978723 (-4675 5550);
DISPLAY INVISIBLE (-4675 5550);
FORCEADD UNIVERSAL_GND..1
(-4725 5425);
FORCEPROP 3 LASTPIN (-4725 5475) SIG_NAME GND\g
J 0
(-4715 5485);
DISPLAY 0.659574 (-4715 5485);
PAINT MONO (-4715 5485);
DISPLAY INVISIBLE (-4715 5485);
FORCEPROP 2 LAST CDS_LIB pure_quanta_power
J 0
(-4725 5425);
DISPLAY INVISIBLE (-4725 5425);
FORCEPROP 1 LAST HDL_POWER GND
J 1
(-4700 5350);
DISPLAY 0.872340 (-4700 5350);
PAINT GREEN (-4700 5350);
DISPLAY INVISIBLE (-4700 5350);
FORCEPROP 1 LAST PATH I12
J 0
(-4650 5425);
DISPLAY 0.872340 (-4650 5425);
PAINT AQUA (-4650 5425);
DISPLAY INVISIBLE (-4650 5425);
FORCEADD Q_RES..2
(-3350 4950);
FORCEPROP 1 LAST LOCATION R6788
J 0
(-3305 5075);
DISPLAY 0.978723 (-3305 5075);
FORCEPROP 0 LAST $SEC 1
J 0
(-3300 5125);
DISPLAY 0.680851 (-3300 5125);
PAINT MONO (-3300 5125);
DISPLAY INVISIBLE (-3300 5125);
FORCEPROP 0 LAST CDS_SEC 1
J 0
(-3300 5125);
DISPLAY 0.680851 (-3300 5125);
DISPLAY INVISIBLE (-3300 5125);
FORCEPROP 1 LASTPIN (-3350 5050) $PN 1
J 0
(-3345 5012);
DISPLAY 0.787234 (-3345 5012);
PAINT MONO (-3345 5012);
FORCEPROP 1 LASTPIN (-3350 4850) $PN 2
J 0
(-3345 4860);
DISPLAY 0.787234 (-3345 4860);
PAINT MONO (-3345 4860);
FORCEPROP 1 LAST WATTAGE 1/20W
J 0
(-3310 4925);
DISPLAY 0.978723 (-3310 4925);
FORCEPROP 1 LAST TOLERANCE 1%
J 0
(-3305 4975);
DISPLAY 0.978723 (-3305 4975);
FORCEPROP 1 LAST VALUE 1K
J 0
(-3305 5025);
DISPLAY 0.978723 (-3305 5025);
FORCEPROP 1 LAST PACK_TYPE 0201LF
J 0
(-3310 4775);
DISPLAY 0.978723 (-3310 4775);
FORCEPROP 1 LAST MATERIAL CHIP
J 0
(-3310 4875);
DISPLAY 0.978723 (-3310 4875);
FORCEPROP 2 LAST CDS_LIB pure_quanta
J 0
(-3350 4950);
DISPLAY INVISIBLE (-3350 4950);
FORCEPROP 1 LAST PATH I13
J 0
(-3300 5125);
DISPLAY 0.978723 (-3300 5125);
PAINT WHITE (-3300 5125);
DISPLAY INVISIBLE (-3300 5125);
FORCEPROP 1 LAST PART_NUMBER CS21001FE07
J 0
(-3310 4825);
DISPLAY 0.978723 (-3310 4825);
DISPLAY INVISIBLE (-3310 4825);
FORCEADD UNIVERSAL_GND..1
(-3350 4525);
FORCEPROP 3 LASTPIN (-3350 4575) SIG_NAME GND\g
J 0
(-3340 4585);
DISPLAY 0.659574 (-3340 4585);
PAINT MONO (-3340 4585);
DISPLAY INVISIBLE (-3340 4585);
FORCEPROP 2 LAST CDS_LIB pure_quanta_power
J 0
(-3350 4525);
DISPLAY INVISIBLE (-3350 4525);
FORCEPROP 1 LAST HDL_POWER GND
J 1
(-3325 4450);
DISPLAY 0.872340 (-3325 4450);
PAINT GREEN (-3325 4450);
DISPLAY INVISIBLE (-3325 4450);
FORCEPROP 1 LAST PATH I14
J 0
(-3275 4525);
DISPLAY 0.872340 (-3275 4525);
PAINT AQUA (-3275 4525);
DISPLAY INVISIBLE (-3275 4525);
FORCEADD UNIVERSAL_GND..1
R 7
(-4500 5150);
FORCEPROP 3 LASTPIN (-4450 5150) SIG_NAME GND\g
J 0
(-4440 5160);
DISPLAY 0.659574 (-4440 5160);
PAINT MONO (-4440 5160);
DISPLAY INVISIBLE (-4440 5160);
FORCEPROP 2 LAST CDS_LIB pure_quanta_power
R 1
J 0
(-4500 5150);
DISPLAY INVISIBLE (-4500 5150);
FORCEPROP 1 LAST HDL_POWER GND
R 1
J 1
(-4575 5175);
DISPLAY 0.872340 (-4575 5175);
PAINT GREEN (-4575 5175);
DISPLAY INVISIBLE (-4575 5175);
FORCEPROP 1 LAST PATH I15
R 1
J 0
(-4500 5225);
DISPLAY 0.872340 (-4500 5225);
PAINT AQUA (-4500 5225);
DISPLAY INVISIBLE (-4500 5225);
FORCEADD OFFPAGE..3
R 2
(-7200 5050);
FORCEPROP 2 LAST $XR1 186 
J 0
(-7600 5050);
DISPLAY 0.638298 (-7600 5050);
PAINT MONO (-7600 5050);
FORCEPROP 2 LAST $XR0 185 
J 0
(-7480 5050);
DISPLAY 0.638298 (-7480 5050);
PAINT MONO (-7480 5050);
FORCEPROP 2 LAST CDS_LIB standard
J 0
(-7200 5050);
DISPLAY INVISIBLE (-7200 5050);
FORCEPROP 1 LAST OFFPAGE TRUE
J 2
(-7525 4925);
DISPLAY 0.872340 (-7525 4925);
PAINT GREEN (-7525 4925);
DISPLAY INVISIBLE (-7525 4925);
FORCEPROP 1 LAST COMMENT_BODY TRUE
J 2
(-7150 4950);
DISPLAY 0.872340 (-7150 4950);
PAINT GREEN (-7150 4950);
DISPLAY INVISIBLE (-7150 4950);
FORCEPROP 2 LAST PATH I2
J 0
(-7150 5125);
DISPLAY 0.680851 (-7150 5125);
DISPLAY INVISIBLE (-7150 5125);
FORCEADD Q_RES..1
(-5450 5100);
FORCEPROP 1 LAST LOCATION R672
J 0
(-5700 5100);
DISPLAY 0.978723 (-5700 5100);
FORCEPROP 0 LAST $SEC 1
J 0
(-5500 5275);
DISPLAY 0.680851 (-5500 5275);
PAINT MONO (-5500 5275);
DISPLAY INVISIBLE (-5500 5275);
FORCEPROP 0 LAST CDS_SEC 1
J 0
(-5500 5275);
DISPLAY 0.680851 (-5500 5275);
DISPLAY INVISIBLE (-5500 5275);
FORCEPROP 1 LASTPIN (-5550 5100) $PN 1
J 0
(-5538 5112);
DISPLAY 0.787234 (-5538 5112);
PAINT MONO (-5538 5112);
FORCEPROP 1 LASTPIN (-5350 5100) $PN 2
J 0
(-5388 5112);
DISPLAY 0.787234 (-5388 5112);
PAINT MONO (-5388 5112);
FORCEPROP 1 LAST MATERIAL CHIP
J 0
(-5625 5175);
DISPLAY 0.787234 (-5625 5175);
FORCEPROP 1 LAST WATTAGE 1/20W
J 2
(-5650 5175);
DISPLAY 0.787234 (-5650 5175);
FORCEPROP 1 LAST PACK_TYPE 0201LF
J 0
(-5425 5175);
DISPLAY 0.787234 (-5425 5175);
FORCEPROP 1 LAST VALUE 33.2
J 2
(-5650 5225);
DISPLAY 0.787234 (-5650 5225);
FORCEPROP 1 LAST TOLERANCE 1%
J 0
(-5625 5225);
DISPLAY 0.787234 (-5625 5225);
FORCEPROP 2 LAST CDS_LIB pure_quanta
J 0
(-5450 5100);
DISPLAY INVISIBLE (-5450 5100);
FORCEPROP 1 LAST PATH I3
J 0
(-5500 5250);
DISPLAY 0.978723 (-5500 5250);
PAINT WHITE (-5500 5250);
DISPLAY INVISIBLE (-5500 5250);
FORCEPROP 1 LAST PART_NUMBER CS03321FE09
J 0
(-5500 5225);
DISPLAY 0.808511 (-5500 5225);
DISPLAY INVISIBLE (-5500 5225);
FORCEADD Q_RES..1
(-5450 5050);
FORCEPROP 1 LAST LOCATION R673
J 0
(-5700 5050);
DISPLAY 0.978723 (-5700 5050);
FORCEPROP 0 LAST $SEC 1
J 0
(-5700 5100);
DISPLAY 0.680851 (-5700 5100);
PAINT MONO (-5700 5100);
DISPLAY INVISIBLE (-5700 5100);
FORCEPROP 0 LAST CDS_SEC 1
J 0
(-5700 5100);
DISPLAY 0.680851 (-5700 5100);
DISPLAY INVISIBLE (-5700 5100);
FORCEPROP 1 LASTPIN (-5550 5050) $PN 1
J 0
(-5538 5062);
DISPLAY 0.787234 (-5538 5062);
PAINT MONO (-5538 5062);
FORCEPROP 1 LASTPIN (-5350 5050) $PN 2
J 0
(-5388 5062);
DISPLAY 0.787234 (-5388 5062);
PAINT MONO (-5388 5062);
FORCEPROP 1 LAST MATERIAL CHIP
J 0
(-5625 5125);
DISPLAY 0.787234 (-5625 5125);
DISPLAY INVISIBLE (-5625 5125);
FORCEPROP 2 LAST CDS_LIB pure_quanta
J 0
(-5450 5050);
DISPLAY INVISIBLE (-5450 5050);
FORCEPROP 1 LAST WATTAGE 1/20W
J 2
(-5650 5125);
DISPLAY 0.787234 (-5650 5125);
DISPLAY INVISIBLE (-5650 5125);
FORCEPROP 1 LAST PACK_TYPE 0201LF
J 0
(-5425 5125);
DISPLAY 0.787234 (-5425 5125);
DISPLAY INVISIBLE (-5425 5125);
FORCEPROP 1 LAST VALUE 33.2
J 2
(-5650 5175);
DISPLAY 0.787234 (-5650 5175);
DISPLAY INVISIBLE (-5650 5175);
FORCEPROP 1 LAST TOLERANCE 1%
J 0
(-5625 5175);
DISPLAY 0.787234 (-5625 5175);
DISPLAY INVISIBLE (-5625 5175);
FORCEPROP 1 LAST PATH I4
J 0
(-5500 5200);
DISPLAY 0.978723 (-5500 5200);
PAINT WHITE (-5500 5200);
DISPLAY INVISIBLE (-5500 5200);
FORCEPROP 1 LAST PART_NUMBER CS03321FE09
J 0
(-5500 5175);
DISPLAY 0.808511 (-5500 5175);
DISPLAY INVISIBLE (-5500 5175);
FORCEADD M24M02DRMN6TP..1
(-4025 5125);
FORCEPROP 1 LAST LOCATION U12
J 0
(-4219 5465);
DISPLAY 0.723404 (-4219 5465);
PAINT GREEN (-4219 5465);
FORCEPROP 0 LAST $SEC 1
J 0
(-4200 5600);
DISPLAY 0.680851 (-4200 5600);
PAINT MONO (-4200 5600);
DISPLAY INVISIBLE (-4200 5600);
FORCEPROP 0 LAST CDS_SEC 1
J 0
(-4200 5600);
DISPLAY 0.680851 (-4200 5600);
DISPLAY INVISIBLE (-4200 5600);
FORCEPROP 0 LASTPIN (-3700 5200) $PN 1
J 0
(-3690 5210);
DISPLAY 0.680851 (-3690 5210);
PAINT MONO (-3690 5210);
FORCEPROP 0 LASTPIN (-3700 5150) $PN 2
J 0
(-3690 5160);
DISPLAY 0.680851 (-3690 5160);
PAINT MONO (-3690 5160);
FORCEPROP 0 LASTPIN (-3700 5100) $PN 3
J 0
(-3690 5110);
DISPLAY 0.680851 (-3690 5110);
PAINT MONO (-3690 5110);
FORCEPROP 0 LASTPIN (-4350 5100) $PN 6
J 2
(-4360 5110);
DISPLAY 0.680851 (-4360 5110);
PAINT MONO (-4360 5110);
FORCEPROP 0 LASTPIN (-4350 5050) $PN 5
J 2
(-4360 5060);
DISPLAY 0.680851 (-4360 5060);
PAINT MONO (-4360 5060);
FORCEPROP 0 LASTPIN (-4350 5200) $PN 8
J 2
(-4360 5210);
DISPLAY 0.680851 (-4360 5210);
PAINT MONO (-4360 5210);
FORCEPROP 0 LASTPIN (-3700 5050) $PN 4
J 0
(-3690 5060);
DISPLAY 0.680851 (-3690 5060);
PAINT MONO (-3690 5060);
FORCEPROP 0 LASTPIN (-4350 5150) $PN 7
J 2
(-4360 5160);
DISPLAY 0.680851 (-4360 5160);
PAINT MONO (-4360 5160);
FORCEPROP 2 LAST PART_TYPE SMLF
J 0
(-4200 5550);
DISPLAY 0.680851 (-4200 5550);
FORCEPROP 1 LAST MATERIAL IC
J 0
(-4219 5257);
DISPLAY 0.723404 (-4219 5257);
PAINT GREEN (-4219 5257);
FORCEPROP 2 LAST VALUE M24M02-DRMN6TP
J 0
(-4200 5500);
DISPLAY 0.680851 (-4200 5500);
FORCEPROP 1 LAST NEEDS_NO_SIZE TRUE
J 0
(-3850 5057);
DISPLAY 0.723404 (-3850 5057);
PAINT GREEN (-3850 5057);
DISPLAY INVISIBLE (-3850 5057);
FORCEPROP 1 LAST CDS_LMAN_SYM_OUTLINE -175,125,175,-125
J 0
(-4025 5125);
DISPLAY 0.468085 (-4025 5125);
PAINT GREEN (-4025 5125);
DISPLAY INVISIBLE (-4025 5125);
FORCEPROP 2 LAST CDS_LIB pure_quanta
J 0
(-4025 5125);
DISPLAY INVISIBLE (-4025 5125);
FORCEPROP 1 LAST PATH I5
J 0
(-3850 5000);
DISPLAY 0.723404 (-3850 5000);
PAINT GREEN (-3850 5000);
DISPLAY INVISIBLE (-3850 5000);
FORCEPROP 1 LAST PART_NUMBER AKE33Z00600
J 0
(-4219 5351);
DISPLAY 0.723404 (-4219 5351);
PAINT GREEN (-4219 5351);
DISPLAY INVISIBLE (-4219 5351);
FORCEADD UNIVERSAL_GND..1
(-3500 4875);
FORCEPROP 3 LASTPIN (-3500 4925) SIG_NAME GND\g
J 0
(-3490 4935);
DISPLAY 0.659574 (-3490 4935);
PAINT MONO (-3490 4935);
DISPLAY INVISIBLE (-3490 4935);
FORCEPROP 2 LAST CDS_LIB pure_quanta_power
J 0
(-3500 4875);
DISPLAY INVISIBLE (-3500 4875);
FORCEPROP 1 LAST HDL_POWER GND
J 1
(-3475 4800);
DISPLAY 0.872340 (-3475 4800);
PAINT GREEN (-3475 4800);
DISPLAY INVISIBLE (-3475 4800);
FORCEPROP 1 LAST PATH I9
J 0
(-3425 4875);
DISPLAY 0.872340 (-3425 4875);
PAINT AQUA (-3425 4875);
DISPLAY INVISIBLE (-3425 4875);
FORCEADD QUANTA_TITLE_BLOCK_C..1
(0 0);
FORCEPROP 0 LAST CDS_CON_LAST_MODIFIED Thu Sep 14 16:13:00 2023
J 0
(-1885 15);
DISPLAY INVISIBLE (-1885 15);
FORCEPROP 1 LAST CUSTOM_TXT_CDS <CON_LAST_MODIFIED>
J 0
(-1885 15);
DISPLAY 0.978723 (-1885 15);
FORCEPROP 2 LAST CUSTOM_TXT_CDS <XR_PAGE_TITLE>
J 0
(-7890 5250);
DISPLAY 0.638298 (-7890 5250);
PAINT PINK (-7890 5250);
DISPLAY INVISIBLE (-7890 5250);
FORCEPROP 1 LAST CUSTOM_TXT_CDS <NAME_2>
J 0
(-3175 50);
FORCEPROP 1 LAST CUSTOM_TXT_CDS <NAME_1>
J 0
(-3175 175);
FORCEPROP 1 LAST CUSTOM_TXT_CDS <Q_NUMBER>
J 0
(-1403 103);
DISPLAY 1.212766 (-1403 103);
FORCEPROP 1 LAST CUSTOM_TXT_CDS <Q_PROJ>
J 0
(-2382 102);
DISPLAY 1.212766 (-2382 102);
FORCEPROP 1 LAST CUSTOM_TXT_CDS <Q_REV>
J 0
(-184 103);
DISPLAY 1.212766 (-184 103);
FORCEPROP 1 LAST CUSTOM_TXT_CDS <CON_PAGE_NUM> OF <CON_TOTAL_PAGES>
J 0
(-446 18);
DISPLAY 0.978723 (-446 18);
FORCEPROP 1 LAST Q_TITLE RETIMER_CPU1_P0(7)
J 0
(-9366 26);
DISPLAY 2.446809 (-9366 26);
PAINT GREEN (-9366 26);
FORCEPROP 2 LAST PAGE_BORDER TRUE
J 0
(-7890 5250);
DISPLAY 0.638298 (-7890 5250);
PAINT PINK (-7890 5250);
DISPLAY INVISIBLE (-7890 5250);
FORCEPROP 1 LAST CDS_LMAN_SYM_OUTLINE -9475,6775,100,-125
J 0
(0 0);
DISPLAY 0.468085 (0 0);
PAINT GREEN (0 0);
DISPLAY INVISIBLE (0 0);
FORCEPROP 2 LAST CDS_LIB pure_quanta
J 0
(0 0);
DISPLAY INVISIBLE (0 0);
FORCEPROP 2 LAST CDS_XR_PAGE_TITLE CR-323 : @T6G_MB_LIB.T6G(SCH_1):PAGE323
J 0
(-7890 5250);
DISPLAY 0.638298 (-7890 5250);
PAINT PINK (-7890 5250);
DISPLAY INVISIBLE (-7890 5250);
FORCEPROP 1 LAST Q_DEPT BU9
J 1
(-3763 49);
DISPLAY 1.957447 (-3763 49);
PAINT GREEN (-3763 49);
DISPLAY INVISIBLE (-3763 49);
FORCEPROP 1 LAST COMMENT_BODY TRUE
J 0
(12 -13);
DISPLAY 0.978723 (12 -13);
PAINT GREEN (12 -13);
DISPLAY INVISIBLE (12 -13);
WIRE 16 -1 (-4725 5600)(-4725 5475);
WIRE 16 -1 (-3350 4850)(-3350 4575);
WIRE 16 -1 (-4350 5150)(-4450 5150);
WIRE 16 -1 (-3700 5050)(-3500 5050);
WIRE 16 -1 (-3500 5050)(-3500 4925);
WIRE 16 -1 (-7150 5050)(-5550 5050);
FORCEPROP 2 LAST SIG_NAME SMB_RT_CPU1_P0_ROM_R_SDA
J 0
(-7060 5060);
DISPLAY 0.680851 (-7060 5060);
WIRE 16 -1 (-4350 5050)(-5350 5050);
FORCEPROP 2 LAST SIG_NAME SMB_RT_CPU1_P0_ROM_SDA
J 0
(-5235 5060);
DISPLAY 0.680851 (-5235 5060);
FORCEPROP 2 LASTPROP $XRERR UNIQUE?
J 0
(-5475 5060);
DISPLAY 0.638298 (-5475 5060);
PAINT MONO (-5475 5060);
DISPLAY INVISIBLE (-5475 5060);
WIRE 16 -1 (-7125 5100)(-5550 5100);
FORCEPROP 2 LAST SIG_NAME SMB_RT_CPU1_P0_ROM_R_SCL
J 0
(-7010 5110);
DISPLAY 0.680851 (-7010 5110);
WIRE 16 -1 (-4350 5100)(-5350 5100);
FORCEPROP 2 LAST SIG_NAME SMB_RT_CPU1_P0_ROM_SCL
J 0
(-5235 5110);
DISPLAY 0.680851 (-5235 5110);
FORCEPROP 2 LASTPROP $XRERR UNIQUE?
J 0
(-5475 5110);
DISPLAY 0.638298 (-5475 5110);
PAINT MONO (-5475 5110);
DISPLAY INVISIBLE (-5475 5110);
WIRE 16 -1 (-4500 5950)(-4500 5900);
WIRE 16 -1 (-4500 5900)(-4500 5200);
WIRE 16 -1 (-4725 5900)(-4500 5900);
WIRE 16 -1 (-4725 5800)(-4725 5900);
WIRE 16 -1 (-4500 5200)(-4350 5200);
WIRE 16 -1 (-3700 5100)(-3350 5100);
FORCEPROP 2 LAST SIG_NAME U12_E2
J 0
(-3585 5110);
DISPLAY 0.680851 (-3585 5110);
FORCEPROP 2 LASTPROP $XRERR UNIQUE?
J 0
(-3825 5110);
DISPLAY 0.638298 (-3825 5110);
PAINT MONO (-3825 5110);
DISPLAY INVISIBLE (-3825 5110);
WIRE 16 -1 (-3350 5100)(-3350 5050);
DOT 1 (-4500 5900);
FORCENOTE
RETIMER EEPRO ADDRESS: 0XA0 (8 BIT) / 0X50 (7 BIT)
(-7200 4425) 0;
DISPLAY LEFT (-7200 4425);
DISPLAY 1.595745 (-7200 4425);
QUIT
